(kicad_pcb
	(version 20260206)
	(generator "pcbnew")
	(generator_version "10.0")
	(general
		(thickness 1.6)
		(legacy_teardrops no)
	)
	(paper "A4")
	(title_block
		(title "04192023_DAF0TMB3IC0_F0TG_MB_C_brd_V02_OCP.brd")
		(comment 1 "Grand Teton / footprint 4188 of 8354 (J28), pads 1-113 of 291")
	)
	(layers
		(0 "F.Cu" signal "TOP")
		(4 "In1.Cu" signal "GND")
		(6 "In2.Cu" signal "IN1")
		(8 "In3.Cu" signal "GND1")
		(10 "In4.Cu" signal "IN2")
		(12 "In5.Cu" signal "GND2")
		(14 "In6.Cu" signal "IN3")
		(16 "In7.Cu" signal "GND3")
		(18 "In8.Cu" signal "VCC")
		(20 "In9.Cu" signal "VCC1")
		(22 "In10.Cu" signal "GND4")
		(24 "In11.Cu" signal "IN4")
		(26 "In12.Cu" signal "GND5")
		(28 "In13.Cu" signal "IN5")
		(30 "In14.Cu" signal "GND6")
		(32 "In15.Cu" signal "IN6")
		(34 "In16.Cu" signal "GND7")
		(2 "B.Cu" signal "BOTTOM")
		(9 "F.Adhes" user "F.Adhesive")
		(11 "B.Adhes" user "B.Adhesive")
		(13 "F.Paste" user "Package Geometry/Pastemask Top")
		(15 "B.Paste" user "Package Geometry/Pastemask Bottom")
		(5 "F.SilkS" user "Ref Des/Silkscreen Top")
		(7 "B.SilkS" user "Ref Des/Silkscreen Bottom")
		(1 "F.Mask" user "Board Geometry/Soldermask Top")
		(3 "B.Mask" user "Board Geometry/Soldermask Bottom")
		(17 "Dwgs.User" user "User.Drawings")
		(19 "Cmts.User" user "User.Comments")
		(21 "Eco1.User" user "User.Eco1")
		(23 "Eco2.User" user "User.Eco2")
		(25 "Edge.Cuts" user "Board Geometry/Outline")
		(27 "Margin" user)
		(31 "F.CrtYd" user "Package Geometry/Place Bound Top")
		(29 "B.CrtYd" user "Package Geometry/Place Bound Bottom")
		(35 "F.Fab" user "Ref Des/Assembly Top")
		(33 "B.Fab" user "Ref Des/Assembly Bottom")
	)
	(footprint ""
		(layer "F.Cu")
		(at 42.289984 -255.560322 180)
		(property "Reference" "J28"
			(at -2.876296 -82.230976 0)
			(unlocked yes)
			(layer "F.SilkS")
			(effects
				(font
					(size 0.7874 0.5842)
					(thickness 0.1524)
				)
			)
		)
		(property "Value" ""
			(at 0 0 180)
			(layer "F.Fab")
			(effects
				(font
					(size 1.27 1.27)
				)
			)
		)
		(duplicate_pad_numbers_are_jumpers no)
		(pad "1" smd rect
			(at -2.050034 -63.324994 90)
			(size 0.519938 1.4986)
			(layers "F.Cu" "F.Mask" "F.Paste")
			(net "P12V_MEM_CPU1")
		)
		(pad "2" smd rect
			(at -2.050034 -62.47511 90)
			(size 0.519938 1.4986)
			(layers "F.Cu" "F.Mask" "F.Paste")
			(net "Net_2284")
		)
		(pad "3" smd rect
			(at -2.050034 -61.624972 90)
			(size 0.519938 1.4986)
			(layers "F.Cu" "F.Mask" "F.Paste")
			(net "P3V3_AUX")
		)
		(pad "4" smd rect
			(at -2.050034 -60.775088 90)
			(size 0.519938 1.4986)
			(layers "F.Cu" "F.Mask" "F.Paste")
			(net "I3C_SPD_DDRC_CPU1_SCL")
		)
		(pad "5" smd rect
			(at -2.050034 -59.92495 90)
			(size 0.519938 1.4986)
			(layers "F.Cu" "F.Mask" "F.Paste")
			(net "I3C_SPD_DDRC_CPU1_SDA")
		)
		(pad "6" smd rect
			(at -2.050034 -59.075066 90)
			(size 0.519938 1.4986)
			(layers "F.Cu" "F.Mask" "F.Paste")
			(net "GND")
		)
		(pad "7" smd rect
			(at -2.050034 -58.224928 90)
			(size 0.519938 1.4986)
			(layers "F.Cu" "F.Mask" "F.Paste")
			(net "M_C_CPU1_SA_DQ<0>")
		)
		(pad "8" smd rect
			(at -2.050034 -57.375044 90)
			(size 0.519938 1.4986)
			(layers "F.Cu" "F.Mask" "F.Paste")
			(net "GND")
		)
		(pad "9" smd rect
			(at -2.050034 -56.524906 90)
			(size 0.519938 1.4986)
			(layers "F.Cu" "F.Mask" "F.Paste")
			(net "M_C_CPU1_SA_DQ<1>")
		)
		(pad "10" smd rect
			(at -2.050034 -55.675022 90)
			(size 0.519938 1.4986)
			(layers "F.Cu" "F.Mask" "F.Paste")
			(net "GND")
		)
		(pad "11" smd rect
			(at -2.050034 -54.824884 90)
			(size 0.519938 1.4986)
			(layers "F.Cu" "F.Mask" "F.Paste")
			(net "M_C_CPU1_SA_DQS_DP<0>")
		)
		(pad "12" smd rect
			(at -2.050034 -53.975 90)
			(size 0.519938 1.4986)
			(layers "F.Cu" "F.Mask" "F.Paste")
			(net "M_C_CPU1_SA_DQS_DN<0>")
		)
		(pad "13" smd rect
			(at -2.050034 -53.125116 90)
			(size 0.519938 1.4986)
			(layers "F.Cu" "F.Mask" "F.Paste")
			(net "GND")
		)
		(pad "14" smd rect
			(at -2.050034 -52.274978 90)
			(size 0.519938 1.4986)
			(layers "F.Cu" "F.Mask" "F.Paste")
			(net "M_C_CPU1_SA_DQ<4>")
		)
		(pad "15" smd rect
			(at -2.050034 -51.425094 90)
			(size 0.519938 1.4986)
			(layers "F.Cu" "F.Mask" "F.Paste")
			(net "GND")
		)
		(pad "16" smd rect
			(at -2.050034 -50.574956 90)
			(size 0.519938 1.4986)
			(layers "F.Cu" "F.Mask" "F.Paste")
			(net "M_C_CPU1_SA_DQ<5>")
		)
		(pad "17" smd rect
			(at -2.050034 -49.725072 90)
			(size 0.519938 1.4986)
			(layers "F.Cu" "F.Mask" "F.Paste")
			(net "GND")
		)
		(pad "18" smd rect
			(at -2.050034 -48.874934 90)
			(size 0.519938 1.4986)
			(layers "F.Cu" "F.Mask" "F.Paste")
			(net "M_C_CPU1_SA_DQ<8>")
		)
		(pad "19" smd rect
			(at -2.050034 -48.02505 90)
			(size 0.519938 1.4986)
			(layers "F.Cu" "F.Mask" "F.Paste")
			(net "GND")
		)
		(pad "20" smd rect
			(at -2.050034 -47.174912 90)
			(size 0.519938 1.4986)
			(layers "F.Cu" "F.Mask" "F.Paste")
			(net "M_C_CPU1_SA_DQ<9>")
		)
		(pad "21" smd rect
			(at -2.050034 -46.325028 90)
			(size 0.519938 1.4986)
			(layers "F.Cu" "F.Mask" "F.Paste")
			(net "GND")
		)
		(pad "22" smd rect
			(at -2.050034 -45.47489 90)
			(size 0.519938 1.4986)
			(layers "F.Cu" "F.Mask" "F.Paste")
			(net "M_C_CPU1_SA_DQS_DP<1>")
		)
		(pad "23" smd rect
			(at -2.050034 -44.625006 90)
			(size 0.519938 1.4986)
			(layers "F.Cu" "F.Mask" "F.Paste")
			(net "M_C_CPU1_SA_DQS_DN<1>")
		)
		(pad "24" smd rect
			(at -2.050034 -43.775122 90)
			(size 0.519938 1.4986)
			(layers "F.Cu" "F.Mask" "F.Paste")
			(net "GND")
		)
		(pad "25" smd rect
			(at -2.050034 -42.924984 90)
			(size 0.519938 1.4986)
			(layers "F.Cu" "F.Mask" "F.Paste")
			(net "M_C_CPU1_SA_DQ<12>")
		)
		(pad "26" smd rect
			(at -2.050034 -42.0751 90)
			(size 0.519938 1.4986)
			(layers "F.Cu" "F.Mask" "F.Paste")
			(net "GND")
		)
		(pad "27" smd rect
			(at -2.050034 -41.224962 90)
			(size 0.519938 1.4986)
			(layers "F.Cu" "F.Mask" "F.Paste")
			(net "M_C_CPU1_SA_DQ<13>")
		)
		(pad "28" smd rect
			(at -2.050034 -40.375078 90)
			(size 0.519938 1.4986)
			(layers "F.Cu" "F.Mask" "F.Paste")
			(net "GND")
		)
		(pad "29" smd rect
			(at -2.050034 -39.52494 90)
			(size 0.519938 1.4986)
			(layers "F.Cu" "F.Mask" "F.Paste")
			(net "M_C_CPU1_SA_DQ<16>")
		)
		(pad "30" smd rect
			(at -2.050034 -38.675056 90)
			(size 0.519938 1.4986)
			(layers "F.Cu" "F.Mask" "F.Paste")
			(net "GND")
		)
		(pad "31" smd rect
			(at -2.050034 -37.824918 90)
			(size 0.519938 1.4986)
			(layers "F.Cu" "F.Mask" "F.Paste")
			(net "M_C_CPU1_SA_DQ<17>")
		)
		(pad "32" smd rect
			(at -2.050034 -36.975034 90)
			(size 0.519938 1.4986)
			(layers "F.Cu" "F.Mask" "F.Paste")
			(net "GND")
		)
		(pad "33" smd rect
			(at -2.050034 -36.124896 90)
			(size 0.519938 1.4986)
			(layers "F.Cu" "F.Mask" "F.Paste")
			(net "M_C_CPU1_SA_DQS_DP<2>")
		)
		(pad "34" smd rect
			(at -2.050034 -35.275012 90)
			(size 0.519938 1.4986)
			(layers "F.Cu" "F.Mask" "F.Paste")
			(net "M_C_CPU1_SA_DQS_DN<2>")
		)
		(pad "35" smd rect
			(at -2.050034 -34.425128 90)
			(size 0.519938 1.4986)
			(layers "F.Cu" "F.Mask" "F.Paste")
			(net "GND")
		)
		(pad "36" smd rect
			(at -2.050034 -33.57499 90)
			(size 0.519938 1.4986)
			(layers "F.Cu" "F.Mask" "F.Paste")
			(net "M_C_CPU1_SA_DQ<20>")
		)
		(pad "37" smd rect
			(at -2.050034 -32.725106 90)
			(size 0.519938 1.4986)
			(layers "F.Cu" "F.Mask" "F.Paste")
			(net "GND")
		)
		(pad "38" smd rect
			(at -2.050034 -31.874968 90)
			(size 0.519938 1.4986)
			(layers "F.Cu" "F.Mask" "F.Paste")
			(net "M_C_CPU1_SA_DQ<21>")
		)
		(pad "39" smd rect
			(at -2.050034 -31.025084 90)
			(size 0.519938 1.4986)
			(layers "F.Cu" "F.Mask" "F.Paste")
			(net "GND")
		)
		(pad "40" smd rect
			(at -2.050034 -30.174946 90)
			(size 0.519938 1.4986)
			(layers "F.Cu" "F.Mask" "F.Paste")
			(net "M_C_CPU1_SA_DQ<24>")
		)
		(pad "41" smd rect
			(at -2.050034 -29.325062 90)
			(size 0.519938 1.4986)
			(layers "F.Cu" "F.Mask" "F.Paste")
			(net "GND")
		)
		(pad "42" smd rect
			(at -2.050034 -28.474924 90)
			(size 0.519938 1.4986)
			(layers "F.Cu" "F.Mask" "F.Paste")
			(net "M_C_CPU1_SA_DQ<25>")
		)
		(pad "43" smd rect
			(at -2.050034 -27.62504 90)
			(size 0.519938 1.4986)
			(layers "F.Cu" "F.Mask" "F.Paste")
			(net "GND")
		)
		(pad "44" smd rect
			(at -2.050034 -26.774902 90)
			(size 0.519938 1.4986)
			(layers "F.Cu" "F.Mask" "F.Paste")
			(net "M_C_CPU1_SA_DQS_DP<3>")
		)
		(pad "45" smd rect
			(at -2.050034 -25.925018 90)
			(size 0.519938 1.4986)
			(layers "F.Cu" "F.Mask" "F.Paste")
			(net "M_C_CPU1_SA_DQS_DN<3>")
		)
		(pad "46" smd rect
			(at -2.050034 -25.07488 90)
			(size 0.519938 1.4986)
			(layers "F.Cu" "F.Mask" "F.Paste")
			(net "GND")
		)
		(pad "47" smd rect
			(at -2.050034 -24.224996 90)
			(size 0.519938 1.4986)
			(layers "F.Cu" "F.Mask" "F.Paste")
			(net "M_C_CPU1_SA_DQ<28>")
		)
		(pad "48" smd rect
			(at -2.050034 -23.375112 90)
			(size 0.519938 1.4986)
			(layers "F.Cu" "F.Mask" "F.Paste")
			(net "GND")
		)
		(pad "49" smd rect
			(at -2.050034 -22.524974 90)
			(size 0.519938 1.4986)
			(layers "F.Cu" "F.Mask" "F.Paste")
			(net "M_C_CPU1_SA_DQ<29>")
		)
		(pad "50" smd rect
			(at -2.050034 -21.67509 90)
			(size 0.519938 1.4986)
			(layers "F.Cu" "F.Mask" "F.Paste")
			(net "GND")
		)
		(pad "51" smd rect
			(at -2.050034 -20.824952 90)
			(size 0.519938 1.4986)
			(layers "F.Cu" "F.Mask" "F.Paste")
			(net "M_C_CPU1_SA_CB<0>")
		)
		(pad "52" smd rect
			(at -2.050034 -19.975068 90)
			(size 0.519938 1.4986)
			(layers "F.Cu" "F.Mask" "F.Paste")
			(net "GND")
		)
		(pad "53" smd rect
			(at -2.050034 -19.12493 90)
			(size 0.519938 1.4986)
			(layers "F.Cu" "F.Mask" "F.Paste")
			(net "M_C_CPU1_SA_CB<1>")
		)
		(pad "54" smd rect
			(at -2.050034 -18.275046 90)
			(size 0.519938 1.4986)
			(layers "F.Cu" "F.Mask" "F.Paste")
			(net "GND")
		)
		(pad "55" smd rect
			(at -2.050034 -17.424908 90)
			(size 0.519938 1.4986)
			(layers "F.Cu" "F.Mask" "F.Paste")
			(net "M_C_CPU1_SA_DQS_DP<4>")
		)
		(pad "56" smd rect
			(at -2.050034 -16.575024 90)
			(size 0.519938 1.4986)
			(layers "F.Cu" "F.Mask" "F.Paste")
			(net "M_C_CPU1_SA_DQS_DN<4>")
		)
		(pad "57" smd rect
			(at -2.050034 -15.724886 90)
			(size 0.519938 1.4986)
			(layers "F.Cu" "F.Mask" "F.Paste")
			(net "GND")
		)
		(pad "58" smd rect
			(at -2.050034 -14.875002 90)
			(size 0.519938 1.4986)
			(layers "F.Cu" "F.Mask" "F.Paste")
			(net "M_C_CPU1_SA_CB<4>")
		)
		(pad "59" smd rect
			(at -2.050034 -14.025118 90)
			(size 0.519938 1.4986)
			(layers "F.Cu" "F.Mask" "F.Paste")
			(net "GND")
		)
		(pad "60" smd rect
			(at -2.050034 -13.17498 90)
			(size 0.519938 1.4986)
			(layers "F.Cu" "F.Mask" "F.Paste")
			(net "M_C_CPU1_SA_CB<5>")
		)
		(pad "61" smd rect
			(at -2.050034 -12.325096 90)
			(size 0.519938 1.4986)
			(layers "F.Cu" "F.Mask" "F.Paste")
			(net "GND")
		)
		(pad "62" smd rect
			(at -2.050034 -11.474958 90)
			(size 0.519938 1.4986)
			(layers "F.Cu" "F.Mask" "F.Paste")
			(net "M_C_CPU1_ALERT_N")
		)
		(pad "63" smd rect
			(at -2.050034 -10.625074 90)
			(size 0.519938 1.4986)
			(layers "F.Cu" "F.Mask" "F.Paste")
			(net "GND")
		)
		(pad "64" smd rect
			(at -2.050034 -9.774936 90)
			(size 0.519938 1.4986)
			(layers "F.Cu" "F.Mask" "F.Paste")
			(net "M_C_CPU1_SA_CS_N<0>")
		)
		(pad "65" smd rect
			(at -2.050034 -8.925052 90)
			(size 0.519938 1.4986)
			(layers "F.Cu" "F.Mask" "F.Paste")
			(net "GND")
		)
		(pad "66" smd rect
			(at -2.050034 -8.074914 90)
			(size 0.519938 1.4986)
			(layers "F.Cu" "F.Mask" "F.Paste")
			(net "M_C_CPU1_SA_CA<0>")
		)
		(pad "67" smd rect
			(at -2.050034 -7.22503 90)
			(size 0.519938 1.4986)
			(layers "F.Cu" "F.Mask" "F.Paste")
			(net "GND")
		)
		(pad "68" smd rect
			(at -2.050034 -6.374892 90)
			(size 0.519938 1.4986)
			(layers "F.Cu" "F.Mask" "F.Paste")
			(net "M_C_CPU1_SA_CA<2>")
		)
		(pad "69" smd rect
			(at -2.050034 -5.525008 90)
			(size 0.519938 1.4986)
			(layers "F.Cu" "F.Mask" "F.Paste")
			(net "GND")
		)
		(pad "70" smd rect
			(at -2.050034 -4.675124 90)
			(size 0.519938 1.4986)
			(layers "F.Cu" "F.Mask" "F.Paste")
			(net "M_C_CPU1_SA_CA<4>")
		)
		(pad "71" smd rect
			(at -2.050034 -3.824986 90)
			(size 0.519938 1.4986)
			(layers "F.Cu" "F.Mask" "F.Paste")
			(net "GND")
		)
		(pad "72" smd rect
			(at -2.050034 -2.975102 90)
			(size 0.519938 1.4986)
			(layers "F.Cu" "F.Mask" "F.Paste")
			(net "M_C_CPU1_SA_CA<6>")
		)
		(pad "73" smd rect
			(at -2.050034 -2.124964 90)
			(size 0.519938 1.4986)
			(layers "F.Cu" "F.Mask" "F.Paste")
			(net "GND")
		)
		(pad "74" smd rect
			(at -2.050034 -1.27508 90)
			(size 0.519938 1.4986)
			(layers "F.Cu" "F.Mask" "F.Paste")
			(net "M_C_CPU1_SA_PAR")
		)
		(pad "75" smd rect
			(at -2.050034 -0.424942 90)
			(size 0.519938 1.4986)
			(layers "F.Cu" "F.Mask" "F.Paste")
			(net "GND")
		)
		(pad "76" smd rect
			(at -2.050034 5.525008 90)
			(size 0.519938 1.4986)
			(layers "F.Cu" "F.Mask" "F.Paste")
			(net "M_C_CPU1_SB_CA<0>")
		)
		(pad "77" smd rect
			(at -2.050034 6.374892 90)
			(size 0.519938 1.4986)
			(layers "F.Cu" "F.Mask" "F.Paste")
			(net "GND")
		)
		(pad "78" smd rect
			(at -2.050034 7.22503 90)
			(size 0.519938 1.4986)
			(layers "F.Cu" "F.Mask" "F.Paste")
			(net "M_C_CPU1_SB_CA<2>")
		)
		(pad "79" smd rect
			(at -2.050034 8.074914 90)
			(size 0.519938 1.4986)
			(layers "F.Cu" "F.Mask" "F.Paste")
			(net "GND")
		)
		(pad "80" smd rect
			(at -2.050034 8.925052 90)
			(size 0.519938 1.4986)
			(layers "F.Cu" "F.Mask" "F.Paste")
			(net "M_C_CPU1_SB_CA<4>")
		)
		(pad "81" smd rect
			(at -2.050034 9.774936 90)
			(size 0.519938 1.4986)
			(layers "F.Cu" "F.Mask" "F.Paste")
			(net "GND")
		)
		(pad "82" smd rect
			(at -2.050034 10.625074 90)
			(size 0.519938 1.4986)
			(layers "F.Cu" "F.Mask" "F.Paste")
			(net "M_C_CPU1_SB_CA<6>")
		)
		(pad "83" smd rect
			(at -2.050034 11.474958 90)
			(size 0.519938 1.4986)
			(layers "F.Cu" "F.Mask" "F.Paste")
			(net "GND")
		)
		(pad "84" smd rect
			(at -2.050034 12.325096 90)
			(size 0.519938 1.4986)
			(layers "F.Cu" "F.Mask" "F.Paste")
			(net "M_C_CPU1_SB_CS_N<0>")
		)
		(pad "85" smd rect
			(at -2.050034 13.17498 90)
			(size 0.519938 1.4986)
			(layers "F.Cu" "F.Mask" "F.Paste")
			(net "GND")
		)
		(pad "86" smd rect
			(at -2.050034 14.025118 90)
			(size 0.519938 1.4986)
			(layers "F.Cu" "F.Mask" "F.Paste")
			(net "M_C_CPU1_SA_RSP<0>")
		)
		(pad "87" smd rect
			(at -2.050034 14.875002 90)
			(size 0.519938 1.4986)
			(layers "F.Cu" "F.Mask" "F.Paste")
			(net "M_C_CPU1_SB_RSP<0>")
		)
		(pad "88" smd rect
			(at -2.050034 15.724886 90)
			(size 0.519938 1.4986)
			(layers "F.Cu" "F.Mask" "F.Paste")
			(net "GND")
		)
		(pad "89" smd rect
			(at -2.050034 16.575024 90)
			(size 0.519938 1.4986)
			(layers "F.Cu" "F.Mask" "F.Paste")
			(net "M_C_CPU1_SB_CB<4>")
		)
		(pad "90" smd rect
			(at -2.050034 17.424908 90)
			(size 0.519938 1.4986)
			(layers "F.Cu" "F.Mask" "F.Paste")
			(net "GND")
		)
		(pad "91" smd rect
			(at -2.050034 18.275046 90)
			(size 0.519938 1.4986)
			(layers "F.Cu" "F.Mask" "F.Paste")
			(net "M_C_CPU1_SB_CB<5>")
		)
		(pad "92" smd rect
			(at -2.050034 19.12493 90)
			(size 0.519938 1.4986)
			(layers "F.Cu" "F.Mask" "F.Paste")
			(net "GND")
		)
		(pad "93" smd rect
			(at -2.050034 19.975068 90)
			(size 0.519938 1.4986)
			(layers "F.Cu" "F.Mask" "F.Paste")
			(net "M_C_CPU1_SB_DQS_DP<9>")
		)
		(pad "94" smd rect
			(at -2.050034 20.824952 90)
			(size 0.519938 1.4986)
			(layers "F.Cu" "F.Mask" "F.Paste")
			(net "M_C_CPU1_SB_DQS_DN<9>")
		)
		(pad "95" smd rect
			(at -2.050034 21.67509 90)
			(size 0.519938 1.4986)
			(layers "F.Cu" "F.Mask" "F.Paste")
			(net "GND")
		)
		(pad "96" smd rect
			(at -2.050034 22.524974 90)
			(size 0.519938 1.4986)
			(layers "F.Cu" "F.Mask" "F.Paste")
			(net "M_C_CPU1_SB_CB<0>")
		)
		(pad "97" smd rect
			(at -2.050034 23.375112 90)
			(size 0.519938 1.4986)
			(layers "F.Cu" "F.Mask" "F.Paste")
			(net "GND")
		)
		(pad "98" smd rect
			(at -2.050034 24.224996 90)
			(size 0.519938 1.4986)
			(layers "F.Cu" "F.Mask" "F.Paste")
			(net "M_C_CPU1_SB_CB<1>")
		)
		(pad "99" smd rect
			(at -2.050034 25.07488 90)
			(size 0.519938 1.4986)
			(layers "F.Cu" "F.Mask" "F.Paste")
			(net "GND")
		)
		(pad "100" smd rect
			(at -2.050034 25.925018 90)
			(size 0.519938 1.4986)
			(layers "F.Cu" "F.Mask" "F.Paste")
			(net "M_C_CPU1_SB_DQ<0>")
		)
		(pad "101" smd rect
			(at -2.050034 26.774902 90)
			(size 0.519938 1.4986)
			(layers "F.Cu" "F.Mask" "F.Paste")
			(net "GND")
		)
		(pad "102" smd rect
			(at -2.050034 27.62504 90)
			(size 0.519938 1.4986)
			(layers "F.Cu" "F.Mask" "F.Paste")
			(net "M_C_CPU1_SB_DQ<1>")
		)
		(pad "103" smd rect
			(at -2.050034 28.474924 90)
			(size 0.519938 1.4986)
			(layers "F.Cu" "F.Mask" "F.Paste")
			(net "GND")
		)
		(pad "104" smd rect
			(at -2.050034 29.325062 90)
			(size 0.519938 1.4986)
			(layers "F.Cu" "F.Mask" "F.Paste")
			(net "M_C_CPU1_SB_DQS_DP<0>")
		)
		(pad "105" smd rect
			(at -2.050034 30.174946 90)
			(size 0.519938 1.4986)
			(layers "F.Cu" "F.Mask" "F.Paste")
			(net "M_C_CPU1_SB_DQS_DN<0>")
		)
		(pad "106" smd rect
			(at -2.050034 31.025084 90)
			(size 0.519938 1.4986)
			(layers "F.Cu" "F.Mask" "F.Paste")
			(net "GND")
		)
		(pad "107" smd rect
			(at -2.050034 31.874968 90)
			(size 0.519938 1.4986)
			(layers "F.Cu" "F.Mask" "F.Paste")
			(net "M_C_CPU1_SB_DQ<4>")
		)
		(pad "108" smd rect
			(at -2.050034 32.725106 90)
			(size 0.519938 1.4986)
			(layers "F.Cu" "F.Mask" "F.Paste")
			(net "GND")
		)
		(pad "109" smd rect
			(at -2.050034 33.57499 90)
			(size 0.519938 1.4986)
			(layers "F.Cu" "F.Mask" "F.Paste")
			(net "M_C_CPU1_SB_DQ<5>")
		)
		(pad "110" smd rect
			(at -2.050034 34.425128 90)
			(size 0.519938 1.4986)
			(layers "F.Cu" "F.Mask" "F.Paste")
			(net "GND")
		)
		(pad "111" smd rect
			(at -2.050034 35.275012 90)
			(size 0.519938 1.4986)
			(layers "F.Cu" "F.Mask" "F.Paste")
			(net "M_C_CPU1_SB_DQ<8>")
		)
		(pad "112" smd rect
			(at -2.050034 36.124896 90)
			(size 0.519938 1.4986)
			(layers "F.Cu" "F.Mask" "F.Paste")
			(net "GND")
		)
		(pad "113" smd rect
			(at -2.050034 36.975034 90)
			(size 0.519938 1.4986)
			(layers "F.Cu" "F.Mask" "F.Paste")
			(net "M_C_CPU1_SB_DQ<9>")
		)
	)
)
